(kicad_pcb
	(version 20260206)
	(generator "pcbnew")
	(generator_version "10.0")
	(general
		(thickness 1.21888)
		(legacy_teardrops no)
	)
	(paper "A4")
	(title_block
		(title "timecard-v8 — TimeCard-DC-V8_EXP.PcbDoc")
		(comment 1 "Time Appliance Project (Time Card) / footprints 209-212 of 288")
	)
	(layers
		(0 "F.Cu" signal "TOP")
		(4 "In1.Cu" signal "SGND")
		(6 "In2.Cu" signal "IN1")
		(8 "In3.Cu" signal "IN2")
		(10 "In4.Cu" signal "SGND1")
		(2 "B.Cu" signal "BOTTOM")
		(9 "F.Adhes" user "F.Adhesive")
		(11 "B.Adhes" user "B.Adhesive")
		(13 "F.Paste" user "Top Paste")
		(15 "B.Paste" user "Bottom Paste")
		(5 "F.SilkS" user "Top Overlay")
		(7 "B.SilkS" user "Bottom Overlay")
		(1 "F.Mask" user "Top Solder")
		(3 "B.Mask" user "Bottom Solder")
		(17 "Dwgs.User" user "User.Drawings")
		(19 "Cmts.User" user "User.Comments")
		(21 "Eco1.User" user "User.Eco1")
		(23 "Eco2.User" user "User.Eco2")
		(25 "Edge.Cuts" user)
		(27 "Margin" user)
		(31 "F.CrtYd" user "Top Courtyard")
		(29 "B.CrtYd" user "Bottom Courtyard")
		(35 "F.Fab" user "Top Component Center")
		(33 "B.Fab" user "Bottom Component Center")
	)
	(footprint "Vault:FP-CC0603-DA-MFG"
		(layer "F.Cu")
		(at 219.8261 114.4162 180)
		(property "Reference" "C3"
			(at -1.2 -1.593345 0)
			(unlocked yes)
			(layer "F.SilkS")
			(effects
				(font
					(size 0.762 0.762)
					(thickness 0.2286)
				)
				(justify left bottom)
			)
		)
		(property "Value" "0.1uF_50V_0603"
			(at -0.7365 8.683155 0)
			(unlocked yes)
			(layer "F.SilkS")
			(hide yes)
			(effects
				(font
					(size 0.762 0.762)
					(thickness 0.2286)
				)
				(justify left bottom)
			)
		)
		(sheetname "POWER")
		(sheetfile "POWER.kicad_sch")
		(duplicate_pad_numbers_are_jumpers no)
		(fp_line
			(start 0.85 0.85)
			(end -0.85 0.85)
			(stroke
				(width 0.2)
				(type solid)
			)
			(layer "F.SilkS")
		)
		(fp_line
			(start 0.85 -0.85)
			(end -0.85 -0.85)
			(stroke
				(width 0.2)
				(type solid)
			)
			(layer "F.SilkS")
		)
		(fp_line
			(start 1.35 0.75)
			(end -1.35 0.75)
			(stroke
				(width 0.2)
				(type solid)
			)
			(layer "F.CrtYd")
		)
		(fp_line
			(start 1.35 -0.75)
			(end 1.35 0.75)
			(stroke
				(width 0.2)
				(type solid)
			)
			(layer "F.CrtYd")
		)
		(fp_line
			(start 1.35 -0.75)
			(end -1.35 -0.75)
			(stroke
				(width 0.2)
				(type solid)
			)
			(layer "F.CrtYd")
		)
		(fp_line
			(start -1.35 -0.75)
			(end -1.35 0.75)
			(stroke
				(width 0.2)
				(type solid)
			)
			(layer "F.CrtYd")
		)
		(fp_line
			(start 1.35 0.75)
			(end -1.35 0.75)
			(stroke
				(width 0.2)
				(type solid)
			)
			(layer "F.Fab")
		)
		(fp_line
			(start 1.35 -0.75)
			(end 1.35 0.75)
			(stroke
				(width 0.2)
				(type solid)
			)
			(layer "F.Fab")
		)
		(fp_line
			(start 1.35 -0.75)
			(end -1.35 -0.75)
			(stroke
				(width 0.2)
				(type solid)
			)
			(layer "F.Fab")
		)
		(fp_line
			(start 0.5 0)
			(end -0.5 0)
			(stroke
				(width 0.1)
				(type solid)
			)
			(layer "F.Fab")
		)
		(fp_line
			(start 0 -0.5)
			(end 0 0.5)
			(stroke
				(width 0.1)
				(type solid)
			)
			(layer "F.Fab")
		)
		(fp_line
			(start -1.35 -0.75)
			(end -1.35 0.75)
			(stroke
				(width 0.2)
				(type solid)
			)
			(layer "F.Fab")
		)
		(fp_text user "${REFERENCE}"
			(at -0.00001 0.09602 180)
			(unlocked yes)
			(layer "F.Fab")
			(effects
				(font
					(face "Arial")
					(size 0.63 0.63)
					(thickness 0.1)
				)
				(justify left bottom)
			)
		)
		(pad "1" smd rect
			(at -0.75 0 180)
			(size 0.8 0.9)
			(layers "F.Cu" "F.Mask" "F.Paste")
			(net "NetC3_1")
			(solder_mask_margin 0)
			(solder_paste_margin 0)
		)
		(pad "2" smd rect
			(at 0.75 0 180)
			(size 0.8 0.9)
			(layers "F.Cu" "F.Mask" "F.Paste")
			(net "NetC3_2")
			(solder_mask_margin 0)
			(solder_paste_margin 0)
		)
	)
	(footprint "Vault:CAPC1005X56X25NL10T15"
		(layer "F.Cu")
		(at 191.1261 89.0162 180)
		(property "Reference" "C66"
			(at -2.2286 -0.326931 0)
			(unlocked yes)
			(layer "F.SilkS")
			(effects
				(font
					(size 0.762 0.762)
					(thickness 0.2286)
				)
			)
		)
		(property "Value" "0.1uF_0402"
			(at 2.06903 2.567191 180)
			(unlocked yes)
			(layer "F.SilkS")
			(hide yes)
			(effects
				(font
					(size 0.762 0.762)
					(thickness 0.2286)
				)
			)
		)
		(sheetname "GPS_IMU_SENSORS")
		(sheetfile "GPS_IMU_SENSORS.kicad_sch")
		(duplicate_pad_numbers_are_jumpers no)
		(pad "1" smd rect
			(at -0.44 0 270)
			(size 0.64 0.68)
			(layers "F.Cu" "F.Mask" "F.Paste")
			(net "GND")
		)
		(pad "2" smd rect
			(at 0.44 0 270)
			(size 0.64 0.68)
			(layers "F.Cu" "F.Mask" "F.Paste")
			(net "+3.3V")
		)
	)
	(footprint "FPGA_CONN:SingleFPGAConn"
		(layer "F.Cu")
		(at 182.5759 133.49995 90)
		(property "Reference" "J37"
			(at -0.39436 -23.455129 90)
			(unlocked yes)
			(layer "F.SilkS")
			(effects
				(font
					(size 0.762 0.762)
					(thickness 0.2286)
				)
			)
		)
		(property "Value" "Single FPGA Conn"
			(at 9.25452 3.621231 90)
			(unlocked yes)
			(layer "F.SilkS")
			(hide yes)
			(effects
				(font
					(size 0.762 0.762)
					(thickness 0.2286)
				)
			)
		)
		(sheetname "FPGA")
		(sheetfile "FPGA.kicad_sch")
		(duplicate_pad_numbers_are_jumpers no)
		(fp_line
			(start 1.40004 -21.2499)
			(end 1.99999 -20.69999)
			(stroke
				(width 0.15011)
				(type solid)
			)
			(layer "F.SilkS")
		)
		(fp_line
			(start -1.40005 -21.2499)
			(end 1.40004 -21.2499)
			(stroke
				(width 0.15011)
				(type solid)
			)
			(layer "F.SilkS")
		)
		(fp_line
			(start -1.40005 -21.2499)
			(end -1.40005 -20.69999)
			(stroke
				(width 0.15011)
				(type solid)
			)
			(layer "F.SilkS")
		)
		(fp_line
			(start 1.99999 -20.69999)
			(end 1.99999 -20.03298)
			(stroke
				(width 0.15011)
				(type solid)
			)
			(layer "F.SilkS")
		)
		(fp_line
			(start -2 -20.69999)
			(end -1.40005 -20.69999)
			(stroke
				(width 0.15011)
				(type solid)
			)
			(layer "F.SilkS")
		)
		(fp_line
			(start -2 -20.69999)
			(end -2 -20.03298)
			(stroke
				(width 0.15011)
				(type solid)
			)
			(layer "F.SilkS")
		)
		(fp_line
			(start 1.99999 0.03302)
			(end 1.99999 0.70002)
			(stroke
				(width 0.15011)
				(type solid)
			)
			(layer "F.SilkS")
		)
		(fp_line
			(start -2 0.03302)
			(end -2 0.70002)
			(stroke
				(width 0.15011)
				(type solid)
			)
			(layer "F.SilkS")
		)
		(fp_line
			(start 1.99999 0.70002)
			(end 1.40004 1.24993)
			(stroke
				(width 0.15011)
				(type solid)
			)
			(layer "F.SilkS")
		)
		(fp_line
			(start -1.40005 0.70002)
			(end -1.40005 1.24993)
			(stroke
				(width 0.15011)
				(type solid)
			)
			(layer "F.SilkS")
		)
		(fp_line
			(start -2 0.70002)
			(end -1.40005 0.70002)
			(stroke
				(width 0.15011)
				(type solid)
			)
			(layer "F.SilkS")
		)
		(fp_line
			(start -1.40005 1.24993)
			(end 1.40004 1.24993)
			(stroke
				(width 0.15011)
				(type solid)
			)
			(layer "F.SilkS")
		)
		(fp_circle
			(center 3.5052 -0.22454)
			(end 3.70535 -0.22454)
			(stroke
				(width 0.40005)
				(type solid)
			)
			(fill no)
			(layer "F.SilkS")
		)
		(pad "1" smd rect
			(at 2.02488 -0.24994 90)
			(size 1.54991 0.24994)
			(layers "F.Cu" "F.Mask" "F.Paste")
		)
		(pad "2" smd rect
			(at -2.02489 -0.24994 90)
			(size 1.54991 0.24994)
			(layers "F.Cu" "F.Mask" "F.Paste")
		)
		(pad "3" smd rect
			(at 2.02488 -0.75006 90)
			(size 1.54991 0.24994)
			(layers "F.Cu" "F.Mask" "F.Paste")
		)
		(pad "4" smd rect
			(at -2.02489 -0.75006 90)
			(size 1.54991 0.24994)
			(layers "F.Cu" "F.Mask" "F.Paste")
		)
		(pad "5" smd rect
			(at 2.02488 -1.24994 90)
			(size 1.54991 0.24994)
			(layers "F.Cu" "F.Mask" "F.Paste")
		)
		(pad "6" smd rect
			(at -2.02489 -1.24994 90)
			(size 1.54991 0.24994)
			(layers "F.Cu" "F.Mask" "F.Paste")
		)
		(pad "7" smd rect
			(at 2.02488 -1.75006 90)
			(size 1.54991 0.24994)
			(layers "F.Cu" "F.Mask" "F.Paste")
		)
		(pad "8" smd rect
			(at -2.02489 -1.75006 90)
			(size 1.54991 0.24994)
			(layers "F.Cu" "F.Mask" "F.Paste")
		)
		(pad "9" smd rect
			(at 2.02488 -2.24993 90)
			(size 1.54991 0.24994)
			(layers "F.Cu" "F.Mask" "F.Paste")
			(net "GND")
		)
		(pad "10" smd rect
			(at -2.02489 -2.24993 90)
			(size 1.54991 0.24994)
			(layers "F.Cu" "F.Mask" "F.Paste")
			(net "GND")
		)
		(pad "11" smd rect
			(at 2.02488 -2.75006 90)
			(size 1.54991 0.24994)
			(layers "F.Cu" "F.Mask" "F.Paste")
		)
		(pad "12" smd rect
			(at -2.02489 -2.75006 90)
			(size 1.54991 0.24994)
			(layers "F.Cu" "F.Mask" "F.Paste")
			(net "PCIE_TX2_P")
		)
		(pad "13" smd rect
			(at 2.02488 -3.24993 90)
			(size 1.54991 0.24994)
			(layers "F.Cu" "F.Mask" "F.Paste")
		)
		(pad "14" smd rect
			(at -2.02489 -3.24993 90)
			(size 1.54991 0.24994)
			(layers "F.Cu" "F.Mask" "F.Paste")
			(net "PCIE_TX2_N")
		)
		(pad "15" smd rect
			(at 2.02488 -3.75006 90)
			(size 1.54991 0.24994)
			(layers "F.Cu" "F.Mask" "F.Paste")
			(net "GND")
		)
		(pad "16" smd rect
			(at -2.02489 -3.75006 90)
			(size 1.54991 0.24994)
			(layers "F.Cu" "F.Mask" "F.Paste")
		)
		(pad "17" smd rect
			(at 2.02488 -4.24993 90)
			(size 1.54991 0.24994)
			(layers "F.Cu" "F.Mask" "F.Paste")
			(net "PCIE_TX3_P")
		)
		(pad "18" smd rect
			(at -2.02489 -4.24993 90)
			(size 1.54991 0.24994)
			(layers "F.Cu" "F.Mask" "F.Paste")
			(net "PCIE_RX2_P")
		)
		(pad "19" smd rect
			(at 2.02488 -4.75006 90)
			(size 1.54991 0.24994)
			(layers "F.Cu" "F.Mask" "F.Paste")
			(net "PCIE_TX3_N")
		)
		(pad "20" smd rect
			(at -2.02489 -4.75006 90)
			(size 1.54991 0.24994)
			(layers "F.Cu" "F.Mask" "F.Paste")
			(net "PCIE_RX2_N")
		)
		(pad "21" smd rect
			(at 2.02488 -5.24993 90)
			(size 1.54991 0.24994)
			(layers "F.Cu" "F.Mask" "F.Paste")
			(net "GND")
		)
		(pad "22" smd rect
			(at -2.02489 -5.24993 90)
			(size 1.54991 0.24994)
			(layers "F.Cu" "F.Mask" "F.Paste")
		)
		(pad "23" smd rect
			(at 2.02488 -5.75005 90)
			(size 1.54991 0.24994)
			(layers "F.Cu" "F.Mask" "F.Paste")
			(net "PCIE_RX3_P")
		)
		(pad "24" smd rect
			(at -2.02489 -5.75005 90)
			(size 1.54991 0.24994)
			(layers "F.Cu" "F.Mask" "F.Paste")
			(net "PCIE_TX1_P")
		)
		(pad "25" smd rect
			(at 2.02488 -6.24993 90)
			(size 1.54991 0.24994)
			(layers "F.Cu" "F.Mask" "F.Paste")
			(net "PCIE_RX3_N")
		)
		(pad "26" smd rect
			(at -2.02489 -6.24993 90)
			(size 1.54991 0.24994)
			(layers "F.Cu" "F.Mask" "F.Paste")
			(net "PCIE_TX1_N")
		)
		(pad "27" smd rect
			(at 2.02488 -6.75005 90)
			(size 1.54991 0.24994)
			(layers "F.Cu" "F.Mask" "F.Paste")
			(net "GND")
		)
		(pad "28" smd rect
			(at -2.02489 -6.75005 90)
			(size 1.54991 0.24994)
			(layers "F.Cu" "F.Mask" "F.Paste")
		)
		(pad "29" smd rect
			(at 2.02488 -7.24992 90)
			(size 1.54991 0.24994)
			(layers "F.Cu" "F.Mask" "F.Paste")
			(net "PCIE_TX0_P")
		)
		(pad "30" smd rect
			(at -2.02489 -7.24992 90)
			(size 1.54991 0.24994)
			(layers "F.Cu" "F.Mask" "F.Paste")
			(net "PCIE_RX1_P")
		)
		(pad "31" smd rect
			(at 2.02488 -7.75005 90)
			(size 1.54991 0.24994)
			(layers "F.Cu" "F.Mask" "F.Paste")
			(net "PCIE_TX0_N")
		)
		(pad "32" smd rect
			(at -2.02489 -7.75005 90)
			(size 1.54991 0.24994)
			(layers "F.Cu" "F.Mask" "F.Paste")
			(net "PCIE_RX1_N")
		)
		(pad "33" smd rect
			(at 2.02488 -8.24992 90)
			(size 1.54991 0.24994)
			(layers "F.Cu" "F.Mask" "F.Paste")
			(net "GND")
		)
		(pad "34" smd rect
			(at -2.02489 -8.24992 90)
			(size 1.54991 0.24994)
			(layers "F.Cu" "F.Mask" "F.Paste")
		)
		(pad "35" smd rect
			(at 2.02488 -8.75005 90)
			(size 1.54991 0.24994)
			(layers "F.Cu" "F.Mask" "F.Paste")
			(net "PCIE_RX0_P")
		)
		(pad "36" smd rect
			(at -2.02489 -8.75005 90)
			(size 1.54991 0.24994)
			(layers "F.Cu" "F.Mask" "F.Paste")
			(net "PCIE_CLK_P")
		)
		(pad "37" smd rect
			(at 2.02488 -9.24992 90)
			(size 1.54991 0.24994)
			(layers "F.Cu" "F.Mask" "F.Paste")
			(net "PCIE_RX0_N")
		)
		(pad "38" smd rect
			(at -2.02489 -9.24992 90)
			(size 1.54991 0.24994)
			(layers "F.Cu" "F.Mask" "F.Paste")
			(net "PCIE_CLK_N")
		)
		(pad "39" smd rect
			(at 2.02488 -9.75005 90)
			(size 1.54991 0.24994)
			(layers "F.Cu" "F.Mask" "F.Paste")
			(net "GND")
		)
		(pad "40" smd rect
			(at -2.02489 -9.75005 90)
			(size 1.54991 0.24994)
			(layers "F.Cu" "F.Mask" "F.Paste")
			(net "GND")
		)
		(pad "41" smd rect
			(at 2.02488 -10.24992 90)
			(size 1.54991 0.24994)
			(layers "F.Cu" "F.Mask" "F.Paste")
		)
		(pad "42" smd rect
			(at -2.02489 -10.24992 90)
			(size 1.54991 0.24994)
			(layers "F.Cu" "F.Mask" "F.Paste")
		)
		(pad "43" smd rect
			(at 2.02488 -10.75004 90)
			(size 1.54991 0.24994)
			(layers "F.Cu" "F.Mask" "F.Paste")
		)
		(pad "44" smd rect
			(at -2.02489 -10.75004 90)
			(size 1.54991 0.24994)
			(layers "F.Cu" "F.Mask" "F.Paste")
		)
		(pad "45" smd rect
			(at 2.02488 -11.24992 90)
			(size 1.54991 0.24994)
			(layers "F.Cu" "F.Mask" "F.Paste")
		)
		(pad "46" smd rect
			(at -2.02489 -11.24992 90)
			(size 1.54991 0.24994)
			(layers "F.Cu" "F.Mask" "F.Paste")
		)
		(pad "47" smd rect
			(at 2.02488 -11.75004 90)
			(size 1.54991 0.24994)
			(layers "F.Cu" "F.Mask" "F.Paste")
		)
		(pad "48" smd rect
			(at -2.02489 -11.75004 90)
			(size 1.54991 0.24994)
			(layers "F.Cu" "F.Mask" "F.Paste")
		)
		(pad "49" smd rect
			(at 2.02488 -12.24991 90)
			(size 1.54991 0.24994)
			(layers "F.Cu" "F.Mask" "F.Paste")
			(net "GND")
		)
		(pad "50" smd rect
			(at -2.02489 -12.24991 90)
			(size 1.54991 0.24994)
			(layers "F.Cu" "F.Mask" "F.Paste")
			(net "GND")
		)
		(pad "51" smd rect
			(at 2.02488 -12.75004 90)
			(size 1.54991 0.24994)
			(layers "F.Cu" "F.Mask" "F.Paste")
		)
		(pad "52" smd rect
			(at -2.02489 -12.75004 90)
			(size 1.54991 0.24994)
			(layers "F.Cu" "F.Mask" "F.Paste")
		)
		(pad "53" smd rect
			(at 2.02488 -13.24991 90)
			(size 1.54991 0.24994)
			(layers "F.Cu" "F.Mask" "F.Paste")
		)
		(pad "54" smd rect
			(at -2.02489 -13.24991 90)
			(size 1.54991 0.24994)
			(layers "F.Cu" "F.Mask" "F.Paste")
		)
		(pad "55" smd rect
			(at 2.02488 -13.75004 90)
			(size 1.54991 0.24994)
			(layers "F.Cu" "F.Mask" "F.Paste")
		)
		(pad "56" smd rect
			(at -2.02489 -13.75004 90)
			(size 1.54991 0.24994)
			(layers "F.Cu" "F.Mask" "F.Paste")
		)
		(pad "57" smd rect
			(at 2.02488 -14.24991 90)
			(size 1.54991 0.24994)
			(layers "F.Cu" "F.Mask" "F.Paste")
		)
		(pad "58" smd rect
			(at -2.02489 -14.24991 90)
			(size 1.54991 0.24994)
			(layers "F.Cu" "F.Mask" "F.Paste")
		)
		(pad "59" smd rect
			(at 2.02488 -14.75004 90)
			(size 1.54991 0.24994)
			(layers "F.Cu" "F.Mask" "F.Paste")
			(net "GND")
		)
		(pad "60" smd rect
			(at -2.02489 -14.75004 90)
			(size 1.54991 0.24994)
			(layers "F.Cu" "F.Mask" "F.Paste")
			(net "GND")
		)
		(pad "61" smd rect
			(at 2.02488 -15.24991 90)
			(size 1.54991 0.24994)
			(layers "F.Cu" "F.Mask" "F.Paste")
		)
		(pad "62" smd rect
			(at -2.02489 -15.24991 90)
			(size 1.54991 0.24994)
			(layers "F.Cu" "F.Mask" "F.Paste")
		)
		(pad "63" smd rect
			(at 2.02488 -15.75003 90)
			(size 1.54991 0.24994)
			(layers "F.Cu" "F.Mask" "F.Paste")
		)
		(pad "64" smd rect
			(at -2.02489 -15.75003 90)
			(size 1.54991 0.24994)
			(layers "F.Cu" "F.Mask" "F.Paste")
		)
		(pad "65" smd rect
			(at 2.02488 -16.24991 90)
			(size 1.54991 0.24994)
			(layers "F.Cu" "F.Mask" "F.Paste")
		)
		(pad "66" smd rect
			(at -2.02489 -16.24991 90)
			(size 1.54991 0.24994)
			(layers "F.Cu" "F.Mask" "F.Paste")
		)
		(pad "67" smd rect
			(at 2.02488 -16.75003 90)
			(size 1.54991 0.24994)
			(layers "F.Cu" "F.Mask" "F.Paste")
		)
		(pad "68" smd rect
			(at -2.02489 -16.75003 90)
			(size 1.54991 0.24994)
			(layers "F.Cu" "F.Mask" "F.Paste")
		)
		(pad "69" smd rect
			(at 2.02488 -17.2499 90)
			(size 1.54991 0.24994)
			(layers "F.Cu" "F.Mask" "F.Paste")
			(net "GND")
		)
		(pad "70" smd rect
			(at -2.02489 -17.2499 90)
			(size 1.54991 0.24994)
			(layers "F.Cu" "F.Mask" "F.Paste")
			(net "GND")
		)
		(pad "71" smd rect
			(at 2.02488 -17.75003 90)
			(size 1.54991 0.24994)
			(layers "F.Cu" "F.Mask" "F.Paste")
		)
		(pad "72" smd rect
			(at -2.02489 -17.75003 90)
			(size 1.54991 0.24994)
			(layers "F.Cu" "F.Mask" "F.Paste")
		)
		(pad "73" smd rect
			(at 2.02488 -18.2499 90)
			(size 1.54991 0.24994)
			(layers "F.Cu" "F.Mask" "F.Paste")
		)
		(pad "74" smd rect
			(at -2.02489 -18.2499 90)
			(size 1.54991 0.24994)
			(layers "F.Cu" "F.Mask" "F.Paste")
		)
		(pad "75" smd rect
			(at 2.02488 -18.75003 90)
			(size 1.54991 0.24994)
			(layers "F.Cu" "F.Mask" "F.Paste")
		)
		(pad "76" smd rect
			(at -2.02489 -18.75003 90)
			(size 1.54991 0.24994)
			(layers "F.Cu" "F.Mask" "F.Paste")
		)
		(pad "77" smd rect
			(at 2.02488 -19.2499 90)
			(size 1.54991 0.24994)
			(layers "F.Cu" "F.Mask" "F.Paste")
		)
		(pad "78" smd rect
			(at -2.02489 -19.2499 90)
			(size 1.54991 0.24994)
			(layers "F.Cu" "F.Mask" "F.Paste")
		)
		(pad "79" smd rect
			(at 2.02488 -19.75003 90)
			(size 1.54991 0.24994)
			(layers "F.Cu" "F.Mask" "F.Paste")
		)
		(pad "80" smd rect
			(at -2.02489 -19.75003 90)
			(size 1.54991 0.24994)
			(layers "F.Cu" "F.Mask" "F.Paste")
		)
		(pad "81" smd rect
			(at 0.01135 1.17626 90)
			(size 1.70002 1.35001)
			(layers "F.Cu" "F.Mask" "F.Paste")
		)
		(pad "82" thru_hole circle
			(at 0 0 90)
			(size 0.55016 0.55016)
			(drill 0.55016)
			(layers "*.Cu" "*.Mask")
			(remove_unused_layers no)
			(thermal_bridge_angle 90)
		)
		(pad "83" thru_hole circle
			(at 0 -19.99996 90)
			(size 0.55016 0.55016)
			(drill 0.55016)
			(layers "*.Cu" "*.Mask")
			(remove_unused_layers no)
			(thermal_bridge_angle 90)
		)
		(pad "84" smd rect
			(at 0.01135 -21.17374 90)
			(size 1.70002 1.35001)
			(layers "F.Cu" "F.Mask" "F.Paste")
		)
	)
	(footprint "Vault:RESC1608X55X30NL15T15"
		(layer "F.Cu")
		(at 105.4261 82.9162)
		(property "Reference" "R27"
			(at 3.2286 0.026931 0)
			(unlocked yes)
			(layer "F.SilkS")
			(effects
				(font
					(size 0.762 0.762)
					(thickness 0.2286)
				)
			)
		)
		(property "Value" "4.7K"
			(at -3.087871 2.37404 270)
			(unlocked yes)
			(layer "F.SilkS")
			(hide yes)
			(effects
				(font
					(size 0.762 0.762)
					(thickness 0.2286)
				)
			)
		)
		(sheetname "GPS_IMU_SENSORS")
		(sheetfile "GPS_IMU_SENSORS.kicad_sch")
		(duplicate_pad_numbers_are_jumpers no)
		(pad "1" smd rect
			(at -0.75 0 90)
			(size 0.95 0.95)
			(layers "F.Cu" "F.Mask" "F.Paste")
			(net "SCL")
		)
		(pad "2" smd rect
			(at 0.75 0 90)
			(size 0.95 0.95)
			(layers "F.Cu" "F.Mask" "F.Paste")
			(net "+3.3V")
		)
	)
)
